# T6G (Grand Teton) — schematic netlist excerpt (pin names and nets, part order shuffled) for the footprints in the layout excerpt that follows; sources: Cadence DE-HDL packaged netlist, KiCad conversion of 04192023_DAF0TMB3IC0_F0TG_MB_C_brd_V02_OCP.brd

R1  Q_RES  49.9 1% CHIP  pkg 0402LF  page 89 : A = I3C_SPD_DDRAF_CPU0_SCL ; B = I3C_SPD_DDRD_CPU0_SCL
PR352  Q_RES  2.2 1% CHIP  pkg 0402LF  page 196 : A = PVDDCR_CPU0_P0_PVCC ; B = PVDDCR_CPU0_P0_VCC5

(kicad_pcb
	(version 20260206)
	(generator "pcbnew")
	(generator_version "10.0")
	(general
		(thickness 1.6)
		(legacy_teardrops no)
	)
	(paper "A4")
	(title_block
		(title "04192023_DAF0TMB3IC0_F0TG_MB_C_brd_V02_OCP.brd")
		(comment 1 "Grand Teton / footprints 7123-7124 of 8354")
	)
	(layers
		(0 "F.Cu" signal "TOP")
		(4 "In1.Cu" signal "GND")
		(6 "In2.Cu" signal "IN1")
		(8 "In3.Cu" signal "GND1")
		(10 "In4.Cu" signal "IN2")
		(12 "In5.Cu" signal "GND2")
		(14 "In6.Cu" signal "IN3")
		(16 "In7.Cu" signal "GND3")
		(18 "In8.Cu" signal "VCC")
		(20 "In9.Cu" signal "VCC1")
		(22 "In10.Cu" signal "GND4")
		(24 "In11.Cu" signal "IN4")
		(26 "In12.Cu" signal "GND5")
		(28 "In13.Cu" signal "IN5")
		(30 "In14.Cu" signal "GND6")
		(32 "In15.Cu" signal "IN6")
		(34 "In16.Cu" signal "GND7")
		(2 "B.Cu" signal "BOTTOM")
		(9 "F.Adhes" user "F.Adhesive")
		(11 "B.Adhes" user "B.Adhesive")
		(13 "F.Paste" user "Package Geometry/Pastemask Top")
		(15 "B.Paste" user "Package Geometry/Pastemask Bottom")
		(5 "F.SilkS" user "Ref Des/Silkscreen Top")
		(7 "B.SilkS" user "Ref Des/Silkscreen Bottom")
		(1 "F.Mask" user "Board Geometry/Soldermask Top")
		(3 "B.Mask" user "Board Geometry/Soldermask Bottom")
		(17 "Dwgs.User" user "User.Drawings")
		(19 "Cmts.User" user "User.Comments")
		(21 "Eco1.User" user "User.Eco1")
		(23 "Eco2.User" user "User.Eco2")
		(25 "Edge.Cuts" user "Board Geometry/Outline")
		(27 "Margin" user)
		(31 "F.CrtYd" user "Package Geometry/Place Bound Top")
		(29 "B.CrtYd" user "Package Geometry/Place Bound Bottom")
		(35 "F.Fab" user "Ref Des/Assembly Top")
		(33 "B.Fab" user "Ref Des/Assembly Bottom")
	)
	(footprint ""
		(layer "B.Cu")
		(at 283.980636 -194.893946 180)
		(property "Reference" "R1"
			(at 0 0 0)
			(layer "B.SilkS")
			(hide yes)
			(effects
				(font
					(size 1.27 1.27)
				)
				(justify mirror)
			)
		)
		(property "Value" ""
			(at 0 0 0)
			(layer "B.Fab")
			(effects
				(font
					(size 1.27 1.27)
				)
				(justify mirror)
			)
		)
		(duplicate_pad_numbers_are_jumpers no)
		(fp_line
			(start 0.7874 0.4064)
			(end 0.7874 -0.4064)
			(stroke
				(width 0.1524)
				(type default)
			)
			(layer "B.SilkS")
		)
		(fp_line
			(start 0.7874 -0.4064)
			(end -0.7874 -0.4064)
			(stroke
				(width 0.1524)
				(type default)
			)
			(layer "B.SilkS")
		)
		(fp_line
			(start -0.7874 0.4064)
			(end 0.7874 0.4064)
			(stroke
				(width 0.1524)
				(type default)
			)
			(layer "B.SilkS")
		)
		(fp_line
			(start -0.7874 -0.4064)
			(end -0.7874 0.4064)
			(stroke
				(width 0.1524)
				(type default)
			)
			(layer "B.SilkS")
		)
		(fp_line
			(start 0.67945 0.3048)
			(end 0.67945 -0.305054)
			(stroke
				(width 0.1)
				(type default)
			)
			(layer "B.Fab")
		)
		(fp_line
			(start 0.67945 -0.305054)
			(end 0.12065 -0.305054)
			(stroke
				(width 0.1)
				(type default)
			)
			(layer "B.Fab")
		)
		(fp_line
			(start 0.12065 0.3048)
			(end 0.67945 0.3048)
			(stroke
				(width 0.1)
				(type default)
			)
			(layer "B.Fab")
		)
		(fp_line
			(start 0.12065 0.2794)
			(end 0.12065 0.3048)
			(stroke
				(width 0.1)
				(type default)
			)
			(layer "B.Fab")
		)
		(fp_line
			(start 0.12065 -0.2794)
			(end -0.12065 -0.2794)
			(stroke
				(width 0.1)
				(type default)
			)
			(layer "B.Fab")
		)
		(fp_line
			(start 0.12065 -0.305054)
			(end 0.12065 -0.2794)
			(stroke
				(width 0.1)
				(type default)
			)
			(layer "B.Fab")
		)
		(fp_line
			(start -0.120396 0.3048)
			(end -0.120396 0.2794)
			(stroke
				(width 0.1)
				(type default)
			)
			(layer "B.Fab")
		)
		(fp_line
			(start -0.120396 0.2794)
			(end 0.12065 0.2794)
			(stroke
				(width 0.1)
				(type default)
			)
			(layer "B.Fab")
		)
		(fp_line
			(start -0.12065 -0.2794)
			(end -0.12065 -0.3048)
			(stroke
				(width 0.1)
				(type default)
			)
			(layer "B.Fab")
		)
		(fp_line
			(start -0.12065 -0.3048)
			(end -0.67945 -0.3048)
			(stroke
				(width 0.1)
				(type default)
			)
			(layer "B.Fab")
		)
		(fp_line
			(start -0.67945 0.3048)
			(end -0.120396 0.3048)
			(stroke
				(width 0.1)
				(type default)
			)
			(layer "B.Fab")
		)
		(fp_line
			(start -0.67945 -0.3048)
			(end -0.67945 0.3048)
			(stroke
				(width 0.1)
				(type default)
			)
			(layer "B.Fab")
		)
		(pad "1" smd circle
			(at 0.40005 0)
			(size 0 0)
			(layers "B.Cu" "B.Mask" "B.Paste")
			(net "I3C_SPD_DDRAF_CPU0_SCL")
		)
		(pad "2" smd circle
			(at -0.40005 0)
			(size 0 0)
			(layers "B.Cu" "B.Mask" "B.Paste")
			(net "I3C_SPD_DDRD_CPU0_SCL")
		)
	)
	(footprint ""
		(layer "B.Cu")
		(at 358.34447 -168.436798 90)
		(property "Reference" "PR352"
			(at 0 0 90)
			(layer "B.SilkS")
			(hide yes)
			(effects
				(font
					(size 1.27 1.27)
				)
				(justify mirror)
			)
		)
		(property "Value" ""
			(at 0 0 90)
			(layer "B.Fab")
			(effects
				(font
					(size 1.27 1.27)
				)
				(justify mirror)
			)
		)
		(duplicate_pad_numbers_are_jumpers no)
		(fp_line
			(start 0.7874 -0.4064)
			(end -0.7874 -0.4064)
			(stroke
				(width 0.1524)
				(type default)
			)
			(layer "B.SilkS")
		)
		(fp_line
			(start -0.7874 -0.4064)
			(end -0.7874 0.4064)
			(stroke
				(width 0.1524)
				(type default)
			)
			(layer "B.SilkS")
		)
		(fp_line
			(start 0.7874 0.4064)
			(end 0.7874 -0.4064)
			(stroke
				(width 0.1524)
				(type default)
			)
			(layer "B.SilkS")
		)
		(fp_line
			(start -0.7874 0.4064)
			(end 0.7874 0.4064)
			(stroke
				(width 0.1524)
				(type default)
			)
			(layer "B.SilkS")
		)
		(fp_line
			(start 0.67945 -0.305054)
			(end 0.12065 -0.305054)
			(stroke
				(width 0.1)
				(type default)
			)
			(layer "B.Fab")
		)
		(fp_line
			(start 0.12065 -0.305054)
			(end 0.12065 -0.2794)
			(stroke
				(width 0.1)
				(type default)
			)
			(layer "B.Fab")
		)
		(fp_line
			(start -0.12065 -0.3048)
			(end -0.67945 -0.3048)
			(stroke
				(width 0.1)
				(type default)
			)
			(layer "B.Fab")
		)
		(fp_line
			(start -0.67945 -0.3048)
			(end -0.67945 0.3048)
			(stroke
				(width 0.1)
				(type default)
			)
			(layer "B.Fab")
		)
		(fp_line
			(start 0.12065 -0.2794)
			(end -0.12065 -0.2794)
			(stroke
				(width 0.1)
				(type default)
			)
			(layer "B.Fab")
		)
		(fp_line
			(start -0.12065 -0.2794)
			(end -0.12065 -0.3048)
			(stroke
				(width 0.1)
				(type default)
			)
			(layer "B.Fab")
		)
		(fp_line
			(start 0.12065 0.2794)
			(end 0.12065 0.3048)
			(stroke
				(width 0.1)
				(type default)
			)
			(layer "B.Fab")
		)
		(fp_line
			(start -0.120396 0.2794)
			(end 0.12065 0.2794)
			(stroke
				(width 0.1)
				(type default)
			)
			(layer "B.Fab")
		)
		(fp_line
			(start 0.67945 0.3048)
			(end 0.67945 -0.305054)
			(stroke
				(width 0.1)
				(type default)
			)
			(layer "B.Fab")
		)
		(fp_line
			(start 0.12065 0.3048)
			(end 0.67945 0.3048)
			(stroke
				(width 0.1)
				(type default)
			)
			(layer "B.Fab")
		)
		(fp_line
			(start -0.120396 0.3048)
			(end -0.120396 0.2794)
			(stroke
				(width 0.1)
				(type default)
			)
			(layer "B.Fab")
		)
		(fp_line
			(start -0.67945 0.3048)
			(end -0.120396 0.3048)
			(stroke
				(width 0.1)
				(type default)
			)
			(layer "B.Fab")
		)
		(pad "1" smd circle
			(at 0.40005 0 270)
			(size 0 0)
			(layers "B.Cu" "B.Mask" "B.Paste")
			(net "PVDDCR_CPU0_P0_PVCC")
		)
		(pad "2" smd circle
			(at -0.40005 0 270)
			(size 0 0)
			(layers "B.Cu" "B.Mask" "B.Paste")
			(net "PVDDCR_CPU0_P0_VCC5")
		)
	)
)
